(kicad_pcb
	(version 20260206)
	(generator "pcbnew")
	(generator_version "10.0")
	(general
		(thickness 1.6)
		(legacy_teardrops no)
	)
	(paper "A4")
	(title_block
		(title "Bryce Canyon_F.DPB_16315-1-OCP.brd")
		(comment 1 "Bryce Canyon / footprints 1078-1079 of 2223")
	)
	(layers
		(0 "F.Cu" signal "TOP")
		(4 "In1.Cu" signal "L2GND")
		(6 "In2.Cu" signal "L3")
		(8 "In3.Cu" signal "L4GND")
		(10 "In4.Cu" signal "L5")
		(12 "In5.Cu" signal "L6VCC")
		(14 "In6.Cu" signal "L7VCC")
		(16 "In7.Cu" signal "L8")
		(18 "In8.Cu" signal "L9GND")
		(20 "In9.Cu" signal "L10")
		(22 "In10.Cu" signal "L11GND")
		(2 "B.Cu" signal "BOTTOM")
		(9 "F.Adhes" user "F.Adhesive")
		(11 "B.Adhes" user "B.Adhesive")
		(13 "F.Paste" user "Package Geometry/Pastemask Top")
		(15 "B.Paste" user "Package Geometry/Pastemask Bottom")
		(5 "F.SilkS" user "Ref Des/Silkscreen Top")
		(7 "B.SilkS" user "Ref Des/Silkscreen Bottom")
		(1 "F.Mask" user "Board Geometry/Soldermask Top")
		(3 "B.Mask" user "Board Geometry/Soldermask Bottom")
		(17 "Dwgs.User" user "User.Drawings")
		(19 "Cmts.User" user "User.Comments")
		(21 "Eco1.User" user "User.Eco1")
		(23 "Eco2.User" user "User.Eco2")
		(25 "Edge.Cuts" user "Board Geometry/Outline")
		(27 "Margin" user)
		(31 "F.CrtYd" user "Package Geometry/Place Bound Top")
		(29 "B.CrtYd" user "Package Geometry/Place Bound Bottom")
		(35 "F.Fab" user "Ref Des/Assembly Top")
		(33 "B.Fab" user "Ref Des/Assembly Bottom")
	)
	(footprint ""
		(layer "F.Cu")
		(at 483.300024 -172.909992 -90)
		(property "Reference" "HDDSAS23"
			(at 0 0 270)
			(layer "F.SilkS")
			(hide yes)
			(effects
				(font
					(size 1.27 1.27)
				)
			)
		)
		(property "Value" "SKT-SAS15P-14P-45-GP"
			(at -20.7645 -8.9789 270)
			(unlocked yes)
			(layer "F.Fab")
			(hide yes)
			(effects
				(font
					(size 1.016 1.016)
					(thickness 0.1524)
				)
			)
		)
		(property "Device Type" "10120818-001C-TRLF"
			(at -20.7645 -10.5029 270)
			(unlocked yes)
			(layer "F.Fab")
			(hide yes)
			(effects
				(font
					(size 1.016 1.016)
					(thickness 0.1524)
				)
			)
		)
		(duplicate_pad_numbers_are_jumpers no)
		(fp_line
			(start 1.651 4.2926)
			(end 1.651 3.0099)
			(stroke
				(width 0.1524)
				(type default)
			)
			(layer "F.SilkS")
		)
		(fp_line
			(start 8.509 4.2926)
			(end 1.651 4.2926)
			(stroke
				(width 0.1524)
				(type default)
			)
			(layer "F.SilkS")
		)
		(fp_line
			(start -23.4188 3.0099)
			(end -23.4188 -3.2512)
			(stroke
				(width 0.1524)
				(type default)
			)
			(layer "F.SilkS")
		)
		(fp_line
			(start 1.651 3.0099)
			(end -23.4188 3.0099)
			(stroke
				(width 0.1524)
				(type default)
			)
			(layer "F.SilkS")
		)
		(fp_line
			(start 8.509 3.0099)
			(end 8.509 4.2926)
			(stroke
				(width 0.1524)
				(type default)
			)
			(layer "F.SilkS")
		)
		(fp_line
			(start 23.4188 3.0099)
			(end 8.509 3.0099)
			(stroke
				(width 0.1524)
				(type default)
			)
			(layer "F.SilkS")
		)
		(fp_line
			(start -23.4188 -3.2512)
			(end 23.4188 -3.2512)
			(stroke
				(width 0.1524)
				(type default)
			)
			(layer "F.SilkS")
		)
		(fp_line
			(start 23.4188 -3.2512)
			(end 23.4188 3.0099)
			(stroke
				(width 0.1524)
				(type default)
			)
			(layer "F.SilkS")
		)
		(fp_line
			(start 15.5067 -3.3401)
			(end 16.2687 -3.3401)
			(stroke
				(width 0.3302)
				(type default)
			)
			(layer "F.SilkS")
		)
		(fp_poly
			(pts
				(xy 15.868904 -3.230372) (xy 16.503904 -3.865372) (xy 15.233904 -3.865372)
			)
			(stroke
				(width 0)
				(type default)
			)
			(fill yes)
			(layer "F.SilkS")
		)
		(fp_poly
			(pts
				(xy -22.8727 -2.7559) (xy 22.8727 -2.7559) (xy 22.8727 2.7559) (xy 8.255 2.7559) (xy 8.255 3.5179)
				(xy 1.905 3.5179) (xy 1.905 2.7559) (xy -22.8727 2.7559)
			)
			(stroke
				(width 0)
				(type default)
			)
			(fill no)
			(layer "F.CrtYd")
		)
		(fp_poly
			(pts
				(xy 1.397 4.5466) (xy 1.397 3.2639) (xy -23.6728 3.2639) (xy -23.6728 -3.5052) (xy 23.6728 -3.5052)
				(xy 23.6728 -0.00635) (xy 22.8727 -0.00635) (xy 22.8727 -2.7559) (xy -22.8727 -2.7559) (xy -22.8727 2.7559)
				(xy 1.905 2.7559) (xy 1.905 3.5179) (xy 8.255 3.5179) (xy 8.255 2.7559) (xy 22.8727 2.7559) (xy 22.8727 0.00635)
				(xy 23.6728 0.00635) (xy 23.6728 3.2639) (xy 8.763 3.2639) (xy 8.763 4.5466)
			)
			(stroke
				(width 0)
				(type default)
			)
			(fill no)
			(layer "F.CrtYd")
		)
		(fp_poly
			(pts
				(xy 1.397 4.5466) (xy 1.397 3.2639) (xy -23.6728 3.2639) (xy -23.6728 -3.5052) (xy 23.6728 -3.5052)
				(xy 23.6728 3.2639) (xy 8.763 3.2639) (xy 8.763 4.5466)
			)
			(stroke
				(width 0)
				(type default)
			)
			(fill no)
			(layer "F.Fab")
		)
		(pad "" np_thru_hole circle
			(at -18.874994 0 270)
			(size 0.254 0.254)
			(drill 1.3462)
			(layers "*.Cu" "*.Mask")
			(clearance 0.9017)
			(thermal_gap 0.9017)
		)
		(pad "" np_thru_hole circle
			(at 18.874994 0 270)
			(size 0.254 0.254)
			(drill 0.9398)
			(layers "*.Cu" "*.Mask")
			(clearance 0.6985)
			(thermal_gap 0.6985)
		)
		(pad "G1" smd rect
			(at 21.874988 0 270)
			(size 2.5908 2.5908)
			(layers "F.Cu" "F.Mask" "F.Paste")
			(net "GND")
		)
		(pad "G2" smd rect
			(at -21.874988 0 270)
			(size 2.5908 2.5908)
			(layers "F.Cu" "F.Mask" "F.Paste")
			(net "GND")
		)
		(pad "P1" smd rect
			(at 1.905 -1.82499 270)
			(size 0.6096 2.3622)
			(layers "F.Cu" "F.Mask" "F.Paste")
			(net "Net_2096")
		)
		(pad "P2" smd rect
			(at 0.635 -1.82499 270)
			(size 0.6096 2.3622)
			(layers "F.Cu" "F.Mask" "F.Paste")
			(net "Net_2097")
		)
		(pad "P3" smd rect
			(at -0.635 -1.82499 270)
			(size 0.6096 2.3622)
			(layers "F.Cu" "F.Mask" "F.Paste")
			(net "Net_2098")
		)
		(pad "P4" smd rect
			(at -1.905 -1.82499 270)
			(size 0.6096 2.3622)
			(layers "F.Cu" "F.Mask" "F.Paste")
			(net "GND")
		)
		(pad "P5" smd rect
			(at -3.175 -1.82499 270)
			(size 0.6096 2.3622)
			(layers "F.Cu" "F.Mask" "F.Paste")
			(net "HDD_PRSNT_23")
		)
		(pad "P6" smd rect
			(at -4.445 -1.82499 270)
			(size 0.6096 2.3622)
			(layers "F.Cu" "F.Mask" "F.Paste")
			(net "GND")
		)
		(pad "P7" smd rect
			(at -5.715 -1.82499 270)
			(size 0.6096 2.3622)
			(layers "F.Cu" "F.Mask" "F.Paste")
			(net "5V_PRE_23")
		)
		(pad "P8" smd rect
			(at -6.985 -1.82499 270)
			(size 0.6096 2.3622)
			(layers "F.Cu" "F.Mask" "F.Paste")
			(net "P5V_HDD23")
		)
		(pad "P9" smd rect
			(at -8.255 -1.82499 270)
			(size 0.6096 2.3622)
			(layers "F.Cu" "F.Mask" "F.Paste")
			(net "P5V_HDD23")
		)
		(pad "P10" smd rect
			(at -9.525 -1.82499 270)
			(size 0.6096 2.3622)
			(layers "F.Cu" "F.Mask" "F.Paste")
			(net "GND")
		)
		(pad "P11" smd rect
			(at -10.795 -1.82499 270)
			(size 0.6096 2.3622)
			(layers "F.Cu" "F.Mask" "F.Paste")
			(net "ACT_HDD_23")
		)
		(pad "P12" smd rect
			(at -12.065 -1.82499 270)
			(size 0.6096 2.3622)
			(layers "F.Cu" "F.Mask" "F.Paste")
			(net "GND")
		)
		(pad "P13" smd rect
			(at -13.335 -1.82499 270)
			(size 0.6096 2.3622)
			(layers "F.Cu" "F.Mask" "F.Paste")
			(net "12V_PRE_23")
		)
		(pad "P14" smd rect
			(at -14.605 -1.82499 270)
			(size 0.6096 2.3622)
			(layers "F.Cu" "F.Mask" "F.Paste")
			(net "P12V_HDD23")
		)
		(pad "P15" smd rect
			(at -15.875 -1.82499 270)
			(size 0.6096 2.3622)
			(layers "F.Cu" "F.Mask" "F.Paste")
			(net "P12V_HDD23")
		)
		(pad "S1" smd rect
			(at 15.875 -1.82499 270)
			(size 0.6096 2.3622)
			(layers "F.Cu" "F.Mask" "F.Paste")
			(net "GND")
		)
		(pad "S2" smd rect
			(at 14.605 -1.82499 270)
			(size 0.6096 2.3622)
			(layers "F.Cu" "F.Mask" "F.Paste")
			(net "SAS_HDD_RX_P23")
		)
		(pad "S3" smd rect
			(at 13.335 -1.82499 270)
			(size 0.6096 2.3622)
			(layers "F.Cu" "F.Mask" "F.Paste")
			(net "SAS_HDD_RX_N23")
		)
		(pad "S4" smd rect
			(at 12.065 -1.82499 270)
			(size 0.6096 2.3622)
			(layers "F.Cu" "F.Mask" "F.Paste")
			(net "GND")
		)
		(pad "S5" smd rect
			(at 10.795 -1.82499 270)
			(size 0.6096 2.3622)
			(layers "F.Cu" "F.Mask" "F.Paste")
			(net "PHY_DRV_A_TO_SCC_A_23_DN")
		)
		(pad "S6" smd rect
			(at 9.525 -1.82499 270)
			(size 0.6096 2.3622)
			(layers "F.Cu" "F.Mask" "F.Paste")
			(net "PHY_DRV_A_TO_SCC_A_23_DP")
		)
		(pad "S7" smd rect
			(at 8.255 -1.82499 270)
			(size 0.6096 2.3622)
			(layers "F.Cu" "F.Mask" "F.Paste")
			(net "GND")
		)
		(pad "S8" smd rect
			(at 7.480046 2.845054 270)
			(size 0.508 2.3622)
			(layers "F.Cu" "F.Mask" "F.Paste")
			(net "GND")
		)
		(pad "S9" smd rect
			(at 6.679946 2.845054 270)
			(size 0.508 2.3622)
			(layers "F.Cu" "F.Mask" "F.Paste")
			(net "Net_461")
		)
		(pad "S10" smd rect
			(at 5.8801 2.845054 270)
			(size 0.508 2.3622)
			(layers "F.Cu" "F.Mask" "F.Paste")
			(net "Net_353")
		)
		(pad "S11" smd rect
			(at 5.08 2.845054 270)
			(size 0.508 2.3622)
			(layers "F.Cu" "F.Mask" "F.Paste")
			(net "GND")
		)
		(pad "S12" smd rect
			(at 4.2799 2.845054 270)
			(size 0.508 2.3622)
			(layers "F.Cu" "F.Mask" "F.Paste")
			(net "Net_389")
		)
		(pad "S13" smd rect
			(at 3.480054 2.845054 270)
			(size 0.508 2.3622)
			(layers "F.Cu" "F.Mask" "F.Paste")
			(net "Net_425")
		)
		(pad "S14" smd rect
			(at 2.679954 2.845054 270)
			(size 0.508 2.3622)
			(layers "F.Cu" "F.Mask" "F.Paste")
			(net "GND")
		)
		(zone
			(layer "F.Cu")
			(hatch none 0.5)
			(connect_pads
				(clearance 0)
			)
			(min_thickness 0.25)
			(keepout
				(tracks not_allowed)
				(vias allowed)
				(pads allowed)
				(copperpour not_allowed)
				(footprints allowed)
			)
			(placement
				(enabled no)
				(sheetname "")
			)
			(fill
				(thermal_gap 0.5)
				(thermal_bridge_width 0.5)
				(island_removal_mode 0)
			)
			(polygon
				(pts
					(xy 486.957624 -189.648592) (xy 479.883724 -189.648592) (xy 479.883724 -196.582792) (xy 480.988624 -196.582792)
					(xy 480.988624 -192.467992) (xy 485.611424 -192.467992) (xy 485.611424 -196.582792) (xy 486.957624 -196.582792)
				)
			)
		)
		(zone
			(layer "F.Cu")
			(hatch none 0.5)
			(connect_pads
				(clearance 0)
			)
			(min_thickness 0.25)
			(keepout
				(tracks allowed)
				(vias not_allowed)
				(pads allowed)
				(copperpour not_allowed)
				(footprints allowed)
			)
			(placement
				(enabled no)
				(sheetname "")
			)
			(fill
				(thermal_gap 0.5)
				(thermal_bridge_width 0.5)
				(island_removal_mode 0)
			)
			(polygon
				(pts
					(xy 486.957624 -189.648592) (xy 479.883724 -189.648592) (xy 479.883724 -196.582792) (xy 480.988624 -196.582792)
					(xy 480.988624 -192.467992) (xy 485.611424 -192.467992) (xy 485.611424 -196.582792) (xy 486.957624 -196.582792)
				)
			)
		)
		(zone
			(layer "F.Cu")
			(hatch none 0.5)
			(connect_pads
				(clearance 0)
			)
			(min_thickness 0.25)
			(keepout
				(tracks not_allowed)
				(vias allowed)
				(pads allowed)
				(copperpour not_allowed)
				(footprints allowed)
			)
			(placement
				(enabled no)
				(sheetname "")
			)
			(fill
				(thermal_gap 0.5)
				(thermal_bridge_width 0.5)
				(island_removal_mode 0)
			)
			(polygon
				(pts
					(xy 486.957624 -156.171392) (xy 479.883724 -156.171392) (xy 479.883724 -149.237192) (xy 480.988624 -149.237192)
					(xy 480.988624 -153.351992) (xy 485.611424 -153.351992) (xy 485.611424 -149.237192) (xy 486.957624 -149.237192)
				)
			)
		)
		(zone
			(layer "F.Cu")
			(hatch none 0.5)
			(connect_pads
				(clearance 0)
			)
			(min_thickness 0.25)
			(keepout
				(tracks allowed)
				(vias not_allowed)
				(pads allowed)
				(copperpour not_allowed)
				(footprints allowed)
			)
			(placement
				(enabled no)
				(sheetname "")
			)
			(fill
				(thermal_gap 0.5)
				(thermal_bridge_width 0.5)
				(island_removal_mode 0)
			)
			(polygon
				(pts
					(xy 486.957624 -156.171392) (xy 479.883724 -156.171392) (xy 479.883724 -149.237192) (xy 480.988624 -149.237192)
					(xy 480.988624 -153.351992) (xy 485.611424 -153.351992) (xy 485.611424 -149.237192) (xy 486.957624 -149.237192)
				)
			)
		)
		(zone
			(layers "F.Cu" "B.Cu" "In1.Cu" "In2.Cu" "In3.Cu" "In4.Cu" "In5.Cu" "In6.Cu"
				"In7.Cu" "In8.Cu" "In9.Cu" "In10.Cu"
			)
			(hatch none 0.5)
			(connect_pads
				(clearance 0)
			)
			(min_thickness 0.25)
			(keepout
				(tracks not_allowed)
				(vias allowed)
				(pads allowed)
				(copperpour not_allowed)
				(footprints allowed)
			)
			(placement
				(enabled no)
				(sheetname "")
			)
			(fill
				(thermal_gap 0.5)
				(thermal_bridge_width 0.5)
				(island_removal_mode 0)
			)
			(polygon
				(pts
					(arc
						(start 484.074724 -154.034998)
						(mid 482.525324 -154.034998)
						(end 484.074724 -154.034998)
					)
				)
			)
		)
		(zone
			(layers "F.Cu" "B.Cu" "In1.Cu" "In2.Cu" "In3.Cu" "In4.Cu" "In5.Cu" "In6.Cu"
				"In7.Cu" "In8.Cu" "In9.Cu" "In10.Cu"
			)
			(hatch none 0.5)
			(connect_pads
				(clearance 0)
			)
			(min_thickness 0.25)
			(keepout
				(tracks not_allowed)
				(vias allowed)
				(pads allowed)
				(copperpour not_allowed)
				(footprints allowed)
			)
			(placement
				(enabled no)
				(sheetname "")
			)
			(fill
				(thermal_gap 0.5)
				(thermal_bridge_width 0.5)
				(island_removal_mode 0)
			)
			(polygon
				(pts
					(arc
						(start 484.277924 -191.784986)
						(mid 482.322124 -191.784986)
						(end 484.277924 -191.784986)
					)
				)
			)
		)
	)
	(footprint ""
		(layer "F.Cu")
		(at 174.382176 -150.260304 -90)
		(property "Reference" "R1062"
			(at 0 0 270)
			(layer "F.SilkS")
			(hide yes)
			(effects
				(font
					(size 1.27 1.27)
				)
			)
		)
		(property "Value" "D001FRL3115F-L-GP"
			(at 3.2766 1.3843 270)
			(unlocked yes)
			(layer "F.Fab")
			(hide yes)
			(effects
				(font
					(size 1.016 1.016)
					(thickness 0.1524)
				)
			)
		)
		(property "Device Type" "RL3115-4PH25"
			(at 3.2766 -0.1397 270)
			(unlocked yes)
			(layer "F.Fab")
			(hide yes)
			(effects
				(font
					(size 1.016 1.016)
					(thickness 0.1524)
				)
			)
		)
		(duplicate_pad_numbers_are_jumpers no)
		(fp_line
			(start -1.9685 1.651)
			(end -1.9685 -1.651)
			(stroke
				(width 0.1524)
				(type default)
			)
			(layer "F.SilkS")
		)
		(fp_line
			(start 1.9685 1.651)
			(end -1.9685 1.651)
			(stroke
				(width 0.1524)
				(type default)
			)
			(layer "F.SilkS")
		)
		(fp_line
			(start -1.9685 -1.651)
			(end 1.9685 -1.651)
			(stroke
				(width 0.1524)
				(type default)
			)
			(layer "F.SilkS")
		)
		(fp_line
			(start 1.9685 -1.651)
			(end 1.9685 1.651)
			(stroke
				(width 0.1524)
				(type default)
			)
			(layer "F.SilkS")
		)
		(fp_line
			(start -2.0828 -1.778)
			(end -2.0828 -0.4445)
			(stroke
				(width 0.3302)
				(type default)
			)
			(layer "F.SilkS")
		)
		(fp_line
			(start -0.5461 -1.778)
			(end -2.0828 -1.778)
			(stroke
				(width 0.3302)
				(type default)
			)
			(layer "F.SilkS")
		)
		(fp_poly
			(pts
				(xy -0.561594 -1.726946) (xy -0.053594 -2.234946) (xy -1.069594 -2.234946)
			)
			(stroke
				(width 0)
				(type default)
			)
			(fill yes)
			(layer "F.SilkS")
		)
		(fp_rect
			(start -1.524 0.7493)
			(end 1.524 -0.7493)
			(stroke
				(width 0)
				(type default)
			)
			(fill no)
			(layer "F.CrtYd")
		)
		(fp_poly
			(pts
				(xy -2.2225 1.905) (xy -2.2225 -1.905) (xy 2.2225 -1.905) (xy 2.2225 -0.7493) (xy -1.524 -0.7493)
				(xy -1.524 0.7493) (xy 1.524 0.7493) (xy 1.524 -0.7366) (xy 2.2225 -0.7366) (xy 2.2225 1.905)
			)
			(stroke
				(width 0)
				(type default)
			)
			(fill no)
			(layer "F.CrtYd")
		)
		(fp_rect
			(start -2.2225 1.905)
			(end 2.2225 -1.905)
			(stroke
				(width 0)
				(type default)
			)
			(fill no)
			(layer "F.Fab")
		)
		(pad "1" smd rect
			(at -0.5715 -0.813562 270)
			(size 2.286 1.143)
			(layers "F.Cu" "F.Mask" "F.Paste")
			(net "P12V_A")
		)
		(pad "2" smd rect
			(at -0.5715 0.813562 270)
			(size 2.286 1.143)
			(layers "F.Cu" "F.Mask" "F.Paste")
			(net "MB0_P12V_R")
		)
		(pad "3" smd rect
			(at 1.334008 -0.813562 270)
			(size 0.762 1.143)
			(layers "F.Cu" "F.Mask" "F.Paste")
			(net "MB0_CM_SENSE_R1_P")
		)
		(pad "4" smd rect
			(at 1.334008 0.813562 270)
			(size 0.762 1.143)
			(layers "F.Cu" "F.Mask" "F.Paste")
			(net "MB0_CM_SENSE_R1_N")
		)
		(zone
			(layer "F.Cu")
			(hatch none 0.5)
			(connect_pads
				(clearance 0)
			)
			(min_thickness 0.25)
			(keepout
				(tracks not_allowed)
				(vias allowed)
				(pads allowed)
				(copperpour not_allowed)
				(footprints allowed)
			)
			(placement
				(enabled no)
				(sheetname "")
			)
			(fill
				(thermal_gap 0.5)
				(thermal_bridge_width 0.5)
				(island_removal_mode 0)
			)
			(polygon
				(pts
					(xy 173.632876 -149.688804) (xy 173.632876 -149.307296) (xy 174.140114 -149.307296) (xy 174.140114 -149.688804)
				)
			)
		)
		(zone
			(layer "F.Cu")
			(hatch none 0.5)
			(connect_pads
				(clearance 0)
			)
			(min_thickness 0.25)
			(keepout
				(tracks allowed)
				(vias not_allowed)
				(pads allowed)
				(copperpour not_allowed)
				(footprints allowed)
			)
			(placement
				(enabled no)
				(sheetname "")
			)
			(fill
				(thermal_gap 0.5)
				(thermal_bridge_width 0.5)
				(island_removal_mode 0)
			)
			(polygon
				(pts
					(xy 173.632876 -149.688804) (xy 173.632876 -149.307296) (xy 174.140114 -149.307296) (xy 174.140114 -149.688804)
				)
			)
		)
		(zone
			(layer "F.Cu")
			(hatch none 0.5)
			(connect_pads
				(clearance 0)
			)
			(min_thickness 0.25)
			(keepout
				(tracks not_allowed)
				(vias allowed)
				(pads allowed)
				(copperpour not_allowed)
				(footprints allowed)
			)
			(placement
				(enabled no)
				(sheetname "")
			)
			(fill
				(thermal_gap 0.5)
				(thermal_bridge_width 0.5)
				(island_removal_mode 0)
			)
			(polygon
				(pts
					(xy 174.624238 -149.688804) (xy 174.624238 -149.307296) (xy 175.131476 -149.307296) (xy 175.131476 -149.688804)
				)
			)
		)
		(zone
			(layer "F.Cu")
			(hatch none 0.5)
			(connect_pads
				(clearance 0)
			)
			(min_thickness 0.25)
			(keepout
				(tracks allowed)
				(vias not_allowed)
				(pads allowed)
				(copperpour not_allowed)
				(footprints allowed)
			)
			(placement
				(enabled no)
				(sheetname "")
			)
			(fill
				(thermal_gap 0.5)
				(thermal_bridge_width 0.5)
				(island_removal_mode 0)
			)
			(polygon
				(pts
					(xy 174.624238 -149.688804) (xy 174.624238 -149.307296) (xy 175.131476 -149.307296) (xy 175.131476 -149.688804)
				)
			)
		)
	)
)
